(kicad_pcb
	(version 20221018)
	(generator pcbnew)
	(general
    (thickness 1.62)
  )
	(paper "A4")
	(title_block
    (title "ECP5 - Datacenter Secure Control Module (DC-SCM)")
    (date "2024-07-01")
    (rev "1.2.1")
		(comment 9 "footprint 50 of 506 (U21), pads 398-492 of 756")
	)
	(layers
    (0 "F.Cu" signal)
    (1 "In1.Cu" power)
    (2 "In2.Cu" signal)
    (3 "In3.Cu" power)
    (4 "In4.Cu" power)
    (5 "In5.Cu" signal)
    (6 "In6.Cu" power)
    (31 "B.Cu" signal)
    (32 "B.Adhes" user "B.Adhesive")
    (33 "F.Adhes" user "F.Adhesive")
    (34 "B.Paste" user)
    (35 "F.Paste" user)
    (36 "B.SilkS" user "B.Silkscreen")
    (37 "F.SilkS" user "F.Silkscreen")
    (38 "B.Mask" user)
    (39 "F.Mask" user)
    (40 "Dwgs.User" user "User.Drawings")
    (41 "Cmts.User" user "User.Comments")
    (42 "Eco1.User" user "User.Eco1")
    (43 "Eco2.User" user "User.Eco2")
    (44 "Edge.Cuts" user)
    (45 "Margin" user)
    (46 "B.CrtYd" user "B.Courtyard")
    (47 "F.CrtYd" user "F.Courtyard")
    (48 "B.Fab" user)
    (49 "F.Fab" user)
  )
	(footprint "antmicro-footprints:BGA-1024-756_27x27mm_Layout32x32_P0.8mm" locked
    (layer "F.Cu")
    (at 104.4 120.55)
    (property "Author" "Antmicro")
    (property "License" "Apache-2.0")
    (property "MPN" "LFE5UM5G-85F-8BG756C")
    (property "Manufacturer" "Lattice Semiconductor")
    (property "Sheetfile" "fpga-power-supply.kicad_sch")
    (property "Sheetname" "FPGA power supply")
    (property "ki_description" "ECP5-5G Field Programmable Gate Array")
    (property "ki_keywords" "SMT, FPGA, IC")
    (attr smd)
    (fp_text reference "U21" (at -12.97 -14.53) (layer "F.SilkS")
        (effects (font (size 0.7 0.7) (thickness 0.127)))
    )
    (fp_text value "ECP5UM5G_85_CABGA756" (at 0 14.5) (layer "F.Fab")
        (effects (font (size 1 1) (thickness 0.15)))
    )
    (pad "E30" smd circle locked (at 10.8 -9.2) (size 0.4 0.4) (layers "F.Cu" "F.Paste" "F.Mask")
      (net 642 "unconnected-(U21D-PR20B-PadE30)") (pinfunction "PR20B") (pintype "bidirectional+no_connect"))
    (pad "E31" smd circle locked (at 11.6 -9.2) (size 0.4 0.4) (layers "F.Cu" "F.Paste" "F.Mask")
      (net 1 "GND") (pinfunction "GND") (pintype "passive"))
    (pad "E32" smd circle locked (at 12.4 -9.2) (size 0.4 0.4) (layers "F.Cu" "F.Paste" "F.Mask")
      (net 643 "unconnected-(U21D-PR23B-PadE32)") (pinfunction "PR23B") (pintype "bidirectional+no_connect"))
    (pad "F1" smd circle locked (at -12.4 -8.4) (size 0.4 0.4) (layers "F.Cu" "F.Paste" "F.Mask")
      (net 662 "ROT_TX") (pinfunction "PL23C") (pintype "bidirectional"))
    (pad "F2" smd circle locked (at -11.6 -8.4) (size 0.4 0.4) (layers "F.Cu" "F.Paste" "F.Mask")
      (net 663 "ROT_RX") (pinfunction "PL23A") (pintype "bidirectional"))
    (pad "F3" smd circle locked (at -10.8 -8.4) (size 0.4 0.4) (layers "F.Cu" "F.Paste" "F.Mask")
      (net 644 "unconnected-(U21H-PL20A-PadF3)") (pinfunction "PL20A") (pintype "bidirectional+no_connect"))
    (pad "F4" smd circle locked (at -10 -8.4) (size 0.4 0.4) (layers "F.Cu" "F.Paste" "F.Mask")
      (net 645 "unconnected-(U21H-PL14C-PadF4)") (pinfunction "PL14C") (pintype "bidirectional+no_connect"))
    (pad "F5" smd circle locked (at -9.2 -8.4) (size 0.4 0.4) (layers "F.Cu" "F.Paste" "F.Mask")
      (net 646 "unconnected-(U21H-PL14D-PadF5)") (pinfunction "PL14D") (pintype "bidirectional+no_connect"))
    (pad "F8" smd circle locked (at -6.8 -8.4) (size 0.4 0.4) (layers "F.Cu" "F.Paste" "F.Mask")
      (net 647 "unconnected-(U21B-PT15A-PadF8)") (pinfunction "PT15A") (pintype "bidirectional+no_connect"))
    (pad "F9" smd circle locked (at -6 -8.4) (size 0.4 0.4) (layers "F.Cu" "F.Paste" "F.Mask")
      (net 648 "unconnected-(U21B-PT22A-PadF9)") (pinfunction "PT22A") (pintype "bidirectional+no_connect"))
    (pad "F10" smd circle locked (at -5.2 -8.4) (size 0.4 0.4) (layers "F.Cu" "F.Paste" "F.Mask")
      (net 649 "unconnected-(U21B-PT27A-PadF10)") (pinfunction "PT27A") (pintype "bidirectional+no_connect"))
    (pad "F11" smd circle locked (at -4.4 -8.4) (size 0.4 0.4) (layers "F.Cu" "F.Paste" "F.Mask")
      (net 650 "unconnected-(U21B-PT33A-PadF11)") (pinfunction "PT33A") (pintype "bidirectional+no_connect"))
    (pad "F13" smd circle locked (at -2.8 -8.4) (size 0.4 0.4) (layers "F.Cu" "F.Paste" "F.Mask")
      (net 651 "unconnected-(U21B-PT40A-PadF13)") (pinfunction "PT40A") (pintype "bidirectional+no_connect"))
    (pad "F14" smd circle locked (at -2 -8.4) (size 0.4 0.4) (layers "F.Cu" "F.Paste" "F.Mask")
      (net 652 "unconnected-(U21B-PT45A-PadF14)") (pinfunction "PT45A") (pintype "bidirectional+no_connect"))
    (pad "F15" smd circle locked (at -1.2 -8.4) (size 0.4 0.4) (layers "F.Cu" "F.Paste" "F.Mask")
      (net 653 "unconnected-(U21B-PT51A-PadF15)") (pinfunction "PT51A") (pintype "bidirectional+no_connect"))
    (pad "F16" smd circle locked (at -0.4 -8.4) (size 0.4 0.4) (layers "F.Cu" "F.Paste" "F.Mask")
      (net 654 "unconnected-(U21B-PT56A-PadF16)") (pinfunction "PT56A") (pintype "bidirectional+no_connect"))
    (pad "F17" smd circle locked (at 0.4 -8.4) (size 0.4 0.4) (layers "F.Cu" "F.Paste" "F.Mask")
      (net 655 "unconnected-(U21C-PT69B-PadF17)") (pinfunction "PT69B") (pintype "bidirectional+no_connect"))
    (pad "F18" smd circle locked (at 1.2 -8.4) (size 0.4 0.4) (layers "F.Cu" "F.Paste" "F.Mask")
      (net 656 "unconnected-(U21C-PT74B-PadF18)") (pinfunction "PT74B") (pintype "bidirectional+no_connect"))
    (pad "F19" smd circle locked (at 2 -8.4) (size 0.4 0.4) (layers "F.Cu" "F.Paste" "F.Mask")
      (net 171 "I3C[2]_SDA_3V3") (pinfunction "PT80B") (pintype "bidirectional"))
    (pad "F20" smd circle locked (at 2.8 -8.4) (size 0.4 0.4) (layers "F.Cu" "F.Paste" "F.Mask")
      (net 170 "I3C[1]_SCL_3V3") (pinfunction "PT85B") (pintype "bidirectional"))
    (pad "F22" smd circle locked (at 4.4 -8.4) (size 0.4 0.4) (layers "F.Cu" "F.Paste" "F.Mask")
      (net 46 "UART1_SCM_TX") (pinfunction "PT92B") (pintype "bidirectional"))
    (pad "F23" smd circle locked (at 5.2 -8.4) (size 0.4 0.4) (layers "F.Cu" "F.Paste" "F.Mask")
      (net 39 "UART1_SCM_RX") (pinfunction "PT98B") (pintype "bidirectional"))
    (pad "F24" smd circle locked (at 6 -8.4) (size 0.4 0.4) (layers "F.Cu" "F.Paste" "F.Mask")
      (net 41 "UART0_SCM_TX") (pinfunction "PT103B") (pintype "bidirectional"))
    (pad "F25" smd circle locked (at 6.8 -8.4) (size 0.4 0.4) (layers "F.Cu" "F.Paste" "F.Mask")
      (net 45 "UART0_SCM_RX") (pinfunction "PT110B") (pintype "bidirectional"))
    (pad "F28" smd circle locked (at 9.2 -8.4) (size 0.4 0.4) (layers "F.Cu" "F.Paste" "F.Mask")
      (net 658 "unconnected-(U21D-PR14D-PadF28)") (pinfunction "PR14D") (pintype "bidirectional+no_connect"))
    (pad "F29" smd circle locked (at 10 -8.4) (size 0.4 0.4) (layers "F.Cu" "F.Paste" "F.Mask")
      (net 667 "unconnected-(U21D-PR14C-PadF29)") (pinfunction "PR14C") (pintype "bidirectional+no_connect"))
    (pad "F30" smd circle locked (at 10.8 -8.4) (size 0.4 0.4) (layers "F.Cu" "F.Paste" "F.Mask")
      (net 668 "unconnected-(U21D-PR20A-PadF30)") (pinfunction "PR20A") (pintype "bidirectional+no_connect"))
    (pad "F31" smd circle locked (at 11.6 -8.4) (size 0.4 0.4) (layers "F.Cu" "F.Paste" "F.Mask")
      (net 669 "unconnected-(U21D-PR23A-PadF31)") (pinfunction "PR23A") (pintype "bidirectional+no_connect"))
    (pad "F32" smd circle locked (at 12.4 -8.4) (size 0.4 0.4) (layers "F.Cu" "F.Paste" "F.Mask")
      (net 670 "unconnected-(U21D-PR23C-PadF32)") (pinfunction "PR23C") (pintype "bidirectional+no_connect"))
    (pad "G9" smd circle locked (at -6 -7.6) (size 0.4 0.4) (layers "F.Cu" "F.Paste" "F.Mask")
      (net 671 "unconnected-(U21A-NC-PadG9)") (pinfunction "NC") (pintype "no_connect"))
    (pad "G10" smd circle locked (at -5.2 -7.6) (size 0.4 0.4) (layers "F.Cu" "F.Paste" "F.Mask")
      (net 673 "unconnected-(U21A-NC-PadG10)") (pinfunction "NC") (pintype "no_connect"))
    (pad "G11" smd circle locked (at -4.4 -7.6) (size 0.4 0.4) (layers "F.Cu" "F.Paste" "F.Mask")
      (net 674 "unconnected-(U21A-NC-PadG11)") (pinfunction "NC") (pintype "no_connect"))
    (pad "G14" smd circle locked (at -2 -7.6) (size 0.4 0.4) (layers "F.Cu" "F.Paste" "F.Mask")
      (net 675 "unconnected-(U21A-NC-PadG14)") (pinfunction "NC") (pintype "no_connect"))
    (pad "G15" smd circle locked (at -1.2 -7.6) (size 0.4 0.4) (layers "F.Cu" "F.Paste" "F.Mask")
      (net 677 "unconnected-(U21A-NC-PadG15)") (pinfunction "NC") (pintype "no_connect"))
    (pad "G16" smd circle locked (at -0.4 -7.6) (size 0.4 0.4) (layers "F.Cu" "F.Paste" "F.Mask")
      (net 682 "unconnected-(U21A-NC-PadG16)") (pinfunction "NC") (pintype "no_connect"))
    (pad "G17" smd circle locked (at 0.4 -7.6) (size 0.4 0.4) (layers "F.Cu" "F.Paste" "F.Mask")
      (net 683 "unconnected-(U21A-NC-PadG17)") (pinfunction "NC") (pintype "no_connect"))
    (pad "G18" smd circle locked (at 1.2 -7.6) (size 0.4 0.4) (layers "F.Cu" "F.Paste" "F.Mask")
      (net 684 "unconnected-(U21A-NC-PadG18)") (pinfunction "NC") (pintype "no_connect"))
    (pad "G19" smd circle locked (at 2 -7.6) (size 0.4 0.4) (layers "F.Cu" "F.Paste" "F.Mask")
      (net 685 "unconnected-(U21A-NC-PadG19)") (pinfunction "NC") (pintype "no_connect"))
    (pad "G22" smd circle locked (at 4.4 -7.6) (size 0.4 0.4) (layers "F.Cu" "F.Paste" "F.Mask")
      (net 704 "unconnected-(U21A-NC-PadG22)") (pinfunction "NC") (pintype "no_connect"))
    (pad "G23" smd circle locked (at 5.2 -7.6) (size 0.4 0.4) (layers "F.Cu" "F.Paste" "F.Mask")
      (net 705 "unconnected-(U21A-NC-PadG23)") (pinfunction "NC") (pintype "no_connect"))
    (pad "G24" smd circle locked (at 6 -7.6) (size 0.4 0.4) (layers "F.Cu" "F.Paste" "F.Mask")
      (net 706 "unconnected-(U21A-NC-PadG24)") (pinfunction "NC") (pintype "no_connect"))
    (pad "H1" smd circle locked (at -12.4 -6.8) (size 0.4 0.4) (layers "F.Cu" "F.Paste" "F.Mask")
      (net 707 "unconnected-(U21H-PL23D-PadH1)") (pinfunction "PL23D") (pintype "bidirectional+no_connect"))
    (pad "H2" smd circle locked (at -11.6 -6.8) (size 0.4 0.4) (layers "F.Cu" "F.Paste" "F.Mask")
      (net 708 "unconnected-(U21H-PL26A-PadH2)") (pinfunction "PL26A") (pintype "bidirectional+no_connect"))
    (pad "H3" smd circle locked (at -10.8 -6.8) (size 0.4 0.4) (layers "F.Cu" "F.Paste" "F.Mask")
      (net 709 "unconnected-(U21H-PL26B-PadH3)") (pinfunction "PL26B") (pintype "bidirectional+no_connect"))
    (pad "H4" smd circle locked (at -10 -6.8) (size 0.4 0.4) (layers "F.Cu" "F.Paste" "F.Mask")
      (net 710 "unconnected-(U21A-NC-PadH4)") (pinfunction "NC") (pintype "no_connect"))
    (pad "H5" smd circle locked (at -9.2 -6.8) (size 0.4 0.4) (layers "F.Cu" "F.Paste" "F.Mask")
      (net 711 "unconnected-(U21H-PL35B-PadH5)") (pinfunction "PL35B") (pintype "bidirectional+no_connect"))
    (pad "H6" smd circle locked (at -8.4 -6.8) (size 0.4 0.4) (layers "F.Cu" "F.Paste" "F.Mask")
      (net 712 "unconnected-(U21H-PL35A-PadH6)") (pinfunction "PL35A") (pintype "bidirectional+no_connect"))
    (pad "H27" smd circle locked (at 8.4 -6.8) (size 0.4 0.4) (layers "F.Cu" "F.Paste" "F.Mask")
      (net 713 "unconnected-(U21D-PR35A-PadH27)") (pinfunction "PR35A") (pintype "bidirectional+no_connect"))
    (pad "H28" smd circle locked (at 9.2 -6.8) (size 0.4 0.4) (layers "F.Cu" "F.Paste" "F.Mask")
      (net 714 "unconnected-(U21D-PR35B-PadH28)") (pinfunction "PR35B") (pintype "bidirectional+no_connect"))
    (pad "H29" smd circle locked (at 10 -6.8) (size 0.4 0.4) (layers "F.Cu" "F.Paste" "F.Mask")
      (net 715 "unconnected-(U21A-NC-PadH29)") (pinfunction "NC") (pintype "no_connect"))
    (pad "H30" smd circle locked (at 10.8 -6.8) (size 0.4 0.4) (layers "F.Cu" "F.Paste" "F.Mask")
      (net 62 "ESPI_RESET_N") (pinfunction "PR26B") (pintype "bidirectional"))
    (pad "H31" smd circle locked (at 11.6 -6.8) (size 0.4 0.4) (layers "F.Cu" "F.Paste" "F.Mask")
      (net 66 "ESPI_IO3") (pinfunction "PR26A") (pintype "bidirectional"))
    (pad "H32" smd circle locked (at 12.4 -6.8) (size 0.4 0.4) (layers "F.Cu" "F.Paste" "F.Mask")
      (net 67 "ESPI_CS1_N") (pinfunction "PR23D") (pintype "bidirectional"))
    (pad "J1" smd circle locked (at -12.4 -6) (size 0.4 0.4) (layers "F.Cu" "F.Paste" "F.Mask")
      (net 716 "unconnected-(U21H-PL29B-PadJ1)") (pinfunction "PL29B") (pintype "bidirectional+no_connect"))
    (pad "J2" smd circle locked (at -11.6 -6) (size 0.4 0.4) (layers "F.Cu" "F.Paste" "F.Mask")
      (net 1 "GND") (pinfunction "GND") (pintype "passive"))
    (pad "J3" smd circle locked (at -10.8 -6) (size 0.4 0.4) (layers "F.Cu" "F.Paste" "F.Mask")
      (net 717 "unconnected-(U21H-PL26C-PadJ3)") (pinfunction "PL26C") (pintype "bidirectional+no_connect"))
    (pad "J4" smd circle locked (at -10 -6) (size 0.4 0.4) (layers "F.Cu" "F.Paste" "F.Mask")
      (net 718 "unconnected-(U21H-PL32C-PadJ4)") (pinfunction "PL32C") (pintype "bidirectional+no_connect"))
    (pad "J5" smd circle locked (at -9.2 -6) (size 0.4 0.4) (layers "F.Cu" "F.Paste" "F.Mask")
      (net 1 "GND") (pinfunction "GND") (pintype "passive"))
    (pad "J6" smd circle locked (at -8.4 -6) (size 0.4 0.4) (layers "F.Cu" "F.Paste" "F.Mask")
      (net 286 "MMC_DAT7") (pinfunction "PL35D") (pintype "bidirectional"))
    (pad "J7" smd circle locked (at -7.6 -6) (size 0.4 0.4) (layers "F.Cu" "F.Paste" "F.Mask")
      (net 287 "MMC_CMD") (pinfunction "PL35C") (pintype "bidirectional"))
    (pad "J26" smd circle locked (at 7.6 -6) (size 0.4 0.4) (layers "F.Cu" "F.Paste" "F.Mask")
      (net 719 "unconnected-(U21D-PR35C-PadJ26)") (pinfunction "PR35C") (pintype "bidirectional+no_connect"))
    (pad "J27" smd circle locked (at 8.4 -6) (size 0.4 0.4) (layers "F.Cu" "F.Paste" "F.Mask")
      (net 720 "unconnected-(U21D-PR35D-PadJ27)") (pinfunction "PR35D") (pintype "bidirectional+no_connect"))
    (pad "J28" smd circle locked (at 9.2 -6) (size 0.4 0.4) (layers "F.Cu" "F.Paste" "F.Mask")
      (net 1 "GND") (pinfunction "GND") (pintype "passive"))
    (pad "J29" smd circle locked (at 10 -6) (size 0.4 0.4) (layers "F.Cu" "F.Paste" "F.Mask")
      (net 721 "unconnected-(U21D-PR32C-PadJ29)") (pinfunction "PR32C") (pintype "bidirectional+no_connect"))
    (pad "J30" smd circle locked (at 10.8 -6) (size 0.4 0.4) (layers "F.Cu" "F.Paste" "F.Mask")
      (net 722 "unconnected-(U21D-PR26C-PadJ30)") (pinfunction "PR26C") (pintype "bidirectional+no_connect"))
    (pad "J31" smd circle locked (at 11.6 -6) (size 0.4 0.4) (layers "F.Cu" "F.Paste" "F.Mask")
      (net 1 "GND") (pinfunction "GND") (pintype "passive"))
    (pad "J32" smd circle locked (at 12.4 -6) (size 0.4 0.4) (layers "F.Cu" "F.Paste" "F.Mask")
      (net 65 "ESPI_IO2") (pinfunction "PR29B") (pintype "bidirectional"))
    (pad "K1" smd circle locked (at -12.4 -5.2) (size 0.4 0.4) (layers "F.Cu" "F.Paste" "F.Mask")
      (net 723 "unconnected-(U21H-PL29C-PadK1)") (pinfunction "PL29C") (pintype "bidirectional+no_connect"))
    (pad "K2" smd circle locked (at -11.6 -5.2) (size 0.4 0.4) (layers "F.Cu" "F.Paste" "F.Mask")
      (net 724 "unconnected-(U21H-PL29A-PadK2)") (pinfunction "PL29A") (pintype "bidirectional+no_connect"))
    (pad "K3" smd circle locked (at -10.8 -5.2) (size 0.4 0.4) (layers "F.Cu" "F.Paste" "F.Mask")
      (net 725 "unconnected-(U21H-PL26D-PadK3)") (pinfunction "PL26D") (pintype "bidirectional+no_connect"))
    (pad "K4" smd circle locked (at -10 -5.2) (size 0.4 0.4) (layers "F.Cu" "F.Paste" "F.Mask")
      (net 726 "unconnected-(U21H-PL32D-PadK4)") (pinfunction "PL32D") (pintype "bidirectional+no_connect"))
    (pad "K5" smd circle locked (at -9.2 -5.2) (size 0.4 0.4) (layers "F.Cu" "F.Paste" "F.Mask")
      (net 284 "MMC_DAT5") (pinfunction "PL38C") (pintype "bidirectional"))
    (pad "K6" smd circle locked (at -8.4 -5.2) (size 0.4 0.4) (layers "F.Cu" "F.Paste" "F.Mask")
      (net 285 "MMC_DAT6") (pinfunction "PL38A") (pintype "bidirectional"))
    (pad "K7" smd circle locked (at -7.6 -5.2) (size 0.4 0.4) (layers "F.Cu" "F.Paste" "F.Mask")
      (net 283 "MMC_DAT4") (pinfunction "PL38B") (pintype "bidirectional"))
    (pad "K10" smd circle locked (at -5.2 -5.2) (size 0.4 0.4) (layers "F.Cu" "F.Paste" "F.Mask")
      (net 1 "GND") (pinfunction "GND") (pintype "passive"))
    (pad "K11" smd circle locked (at -4.4 -5.2) (size 0.4 0.4) (layers "F.Cu" "F.Paste" "F.Mask")
      (net 1 "GND") (pinfunction "GND") (pintype "passive"))
    (pad "K12" smd circle locked (at -3.6 -5.2) (size 0.4 0.4) (layers "F.Cu" "F.Paste" "F.Mask")
      (net 2 "VCC3V3") (pinfunction "VCCIO0") (pintype "power_in"))
    (pad "K13" smd circle locked (at -2.8 -5.2) (size 0.4 0.4) (layers "F.Cu" "F.Paste" "F.Mask")
      (net 304 "/FPGA power supply/VCCAUX") (pinfunction "VCCAUX") (pintype "passive"))
    (pad "K14" smd circle locked (at -2 -5.2) (size 0.4 0.4) (layers "F.Cu" "F.Paste" "F.Mask")
      (net 2 "VCC3V3") (pinfunction "VCCIO0") (pintype "passive"))
    (pad "K15" smd circle locked (at -1.2 -5.2) (size 0.4 0.4) (layers "F.Cu" "F.Paste" "F.Mask")
      (net 2 "VCC3V3") (pinfunction "VCCIO0") (pintype "passive"))
    (pad "K16" smd circle locked (at -0.4 -5.2) (size 0.4 0.4) (layers "F.Cu" "F.Paste" "F.Mask")
      (net 2 "VCC3V3") (pinfunction "VCCIO0") (pintype "passive"))
    (pad "K17" smd circle locked (at 0.4 -5.2) (size 0.4 0.4) (layers "F.Cu" "F.Paste" "F.Mask")
      (net 2 "VCC3V3") (pinfunction "VCCIO1") (pintype "power_in"))
    (pad "K18" smd circle locked (at 1.2 -5.2) (size 0.4 0.4) (layers "F.Cu" "F.Paste" "F.Mask")
      (net 2 "VCC3V3") (pinfunction "VCCIO1") (pintype "passive"))
    (pad "K19" smd circle locked (at 2 -5.2) (size 0.4 0.4) (layers "F.Cu" "F.Paste" "F.Mask")
      (net 2 "VCC3V3") (pinfunction "VCCIO1") (pintype "passive"))
    (pad "K20" smd circle locked (at 2.8 -5.2) (size 0.4 0.4) (layers "F.Cu" "F.Paste" "F.Mask")
      (net 304 "/FPGA power supply/VCCAUX") (pinfunction "VCCAUX") (pintype "passive"))
    (pad "K21" smd circle locked (at 3.6 -5.2) (size 0.4 0.4) (layers "F.Cu" "F.Paste" "F.Mask")
      (net 2 "VCC3V3") (pinfunction "VCCIO1") (pintype "passive"))
    (pad "K22" smd circle locked (at 4.4 -5.2) (size 0.4 0.4) (layers "F.Cu" "F.Paste" "F.Mask")
      (net 1 "GND") (pinfunction "GND") (pintype "passive"))
    (pad "K23" smd circle locked (at 5.2 -5.2) (size 0.4 0.4) (layers "F.Cu" "F.Paste" "F.Mask")
      (net 1 "GND") (pinfunction "GND") (pintype "passive"))
    (pad "K26" smd circle locked (at 7.6 -5.2) (size 0.4 0.4) (layers "F.Cu" "F.Paste" "F.Mask")
      (net 727 "unconnected-(U21D-PR38B-PadK26)") (pinfunction "PR38B") (pintype "bidirectional+no_connect"))
    (pad "K27" smd circle locked (at 8.4 -5.2) (size 0.4 0.4) (layers "F.Cu" "F.Paste" "F.Mask")
      (net 728 "unconnected-(U21D-PR38A-PadK27)") (pinfunction "PR38A") (pintype "bidirectional+no_connect"))
    (pad "K28" smd circle locked (at 9.2 -5.2) (size 0.4 0.4) (layers "F.Cu" "F.Paste" "F.Mask")
      (net 729 "unconnected-(U21D-PR38C-PadK28)") (pinfunction "PR38C") (pintype "bidirectional+no_connect"))
    (pad "K29" smd circle locked (at 10 -5.2) (size 0.4 0.4) (layers "F.Cu" "F.Paste" "F.Mask")
      (net 730 "unconnected-(U21D-PR32D-PadK29)") (pinfunction "PR32D") (pintype "bidirectional+no_connect"))
    (pad "K30" smd circle locked (at 10.8 -5.2) (size 0.4 0.4) (layers "F.Cu" "F.Paste" "F.Mask")
      (net 61 "ESPI_ALERT_N") (pinfunction "PR26D") (pintype "bidirectional"))
    (pad "K31" smd circle locked (at 11.6 -5.2) (size 0.4 0.4) (layers "F.Cu" "F.Paste" "F.Mask")
      (net 64 "ESPI_IO1") (pinfunction "PR29A") (pintype "bidirectional"))
    (pad "K32" smd circle locked (at 12.4 -5.2) (size 0.4 0.4) (layers "F.Cu" "F.Paste" "F.Mask")
      (net 63 "ESPI_IO0") (pinfunction "PR29C") (pintype "bidirectional"))
  )
)
